(kicad_pcb
	(version 20260206)
	(generator "pcbnew")
	(generator_version "10.0")
	(general
		(thickness 1.6)
		(legacy_teardrops no)
	)
	(paper "A4")
	(title_block
		(title "01162023_DA0F0TEBIF0_F0T_Expander_BD_F_brd_V02_OCP.brd")
		(comment 1 "Grand Teton / footprint 6619 of 9728 (PEX0), pads 1652-1765 of 2397")
	)
	(layers
		(0 "F.Cu" signal "TOP")
		(4 "In1.Cu" signal "GND")
		(6 "In2.Cu" signal "VCC")
		(8 "In3.Cu" signal "VCC1")
		(10 "In4.Cu" signal "GND1")
		(12 "In5.Cu" signal "IN1")
		(14 "In6.Cu" signal "GND2")
		(16 "In7.Cu" signal "IN2")
		(18 "In8.Cu" signal "GND3")
		(20 "In9.Cu" signal "IN3")
		(22 "In10.Cu" signal "GND4")
		(24 "In11.Cu" signal "IN4")
		(26 "In12.Cu" signal "GND5")
		(28 "In13.Cu" signal "IN5")
		(30 "In14.Cu" signal "GND6")
		(32 "In15.Cu" signal "IN6")
		(34 "In16.Cu" signal "GND7")
		(2 "B.Cu" signal "BOTTOM")
		(9 "F.Adhes" user "F.Adhesive")
		(11 "B.Adhes" user "B.Adhesive")
		(13 "F.Paste" user "Package Geometry/Pastemask Top")
		(15 "B.Paste" user "Package Geometry/Pastemask Bottom")
		(5 "F.SilkS" user "Ref Des/Silkscreen Top")
		(7 "B.SilkS" user "Ref Des/Silkscreen Bottom")
		(1 "F.Mask" user "Board Geometry/Soldermask Top")
		(3 "B.Mask" user "Board Geometry/Soldermask Bottom")
		(17 "Dwgs.User" user "User.Drawings")
		(19 "Cmts.User" user "User.Comments")
		(21 "Eco1.User" user "User.Eco1")
		(23 "Eco2.User" user "User.Eco2")
		(25 "Edge.Cuts" user "Board Geometry/Outline")
		(27 "Margin" user)
		(31 "F.CrtYd" user "Package Geometry/Place Bound Top")
		(29 "B.CrtYd" user "Package Geometry/Place Bound Bottom")
		(35 "F.Fab" user "Ref Des/Assembly Top")
		(33 "B.Fab" user "Ref Des/Assembly Bottom")
	)
	(footprint ""
		(layer "F.Cu")
		(at 59.649868 -295.89984)
		(property "Reference" "PEX0"
			(at -3.360166 35.566858 0)
			(unlocked yes)
			(layer "F.SilkS")
			(effects
				(font
					(size 2.032 1.524)
					(thickness 0.1524)
				)
				(justify left)
			)
		)
		(property "Value" ""
			(at 0 0 0)
			(layer "F.Fab")
			(effects
				(font
					(size 1.27 1.27)
				)
			)
		)
		(duplicate_pad_numbers_are_jumpers no)
		(pad "E39" smd circle
			(at 13.299948 -18.999962)
			(size 0.4572 0.4572)
			(layers "F.Cu" "F.Mask" "F.Paste")
			(net "GND")
		)
		(pad "E40" smd circle
			(at 14.249908 -18.999962)
			(size 0.4572 0.4572)
			(layers "F.Cu" "F.Mask" "F.Paste")
			(net "GND")
		)
		(pad "E41" smd circle
			(at 15.200122 -18.999962)
			(size 0.4572 0.4572)
			(layers "F.Cu" "F.Mask" "F.Paste")
			(net "GND")
		)
		(pad "E42" smd circle
			(at 16.150082 -18.999962)
			(size 0.4572 0.4572)
			(layers "F.Cu" "F.Mask" "F.Paste")
			(net "GND")
		)
		(pad "E43" smd circle
			(at 17.100042 -18.999962)
			(size 0.4572 0.4572)
			(layers "F.Cu" "F.Mask" "F.Paste")
			(net "GND")
		)
		(pad "E44" smd circle
			(at 18.050002 -18.999962)
			(size 0.4572 0.4572)
			(layers "F.Cu" "F.Mask" "F.Paste")
			(net "GND")
		)
		(pad "E45" smd circle
			(at 18.999962 -18.999962)
			(size 0.4572 0.4572)
			(layers "F.Cu" "F.Mask" "F.Paste")
			(net "GND")
		)
		(pad "E46" smd circle
			(at 19.949922 -18.999962)
			(size 0.4572 0.4572)
			(layers "F.Cu" "F.Mask" "F.Paste")
			(net "GND")
		)
		(pad "E47" smd circle
			(at 20.899882 -18.999962)
			(size 0.4572 0.4572)
			(layers "F.Cu" "F.Mask" "F.Paste")
			(net "GND")
		)
		(pad "E48" smd circle
			(at 21.850096 -18.999962)
			(size 0.4572 0.4572)
			(layers "F.Cu" "F.Mask" "F.Paste")
			(net "P5E_PEX0_STN4_TX_DP<71>")
		)
		(pad "E49" smd circle
			(at 22.800056 -18.999962)
			(size 0.4572 0.4572)
			(layers "F.Cu" "F.Mask" "F.Paste")
			(net "P5E_PEX0_STN4_TX_DN<71>")
		)
		(pad "F1" smd circle
			(at -22.800056 -18.050002)
			(size 0.4572 0.4572)
			(layers "F.Cu" "F.Mask" "F.Paste")
			(net "GND")
		)
		(pad "F2" smd circle
			(at -21.850096 -18.050002)
			(size 0.4572 0.4572)
			(layers "F.Cu" "F.Mask" "F.Paste")
			(net "GND")
		)
		(pad "F3" smd circle
			(at -20.899882 -18.050002)
			(size 0.4572 0.4572)
			(layers "F.Cu" "F.Mask" "F.Paste")
			(net "P5E_PEX0_STN7_TX_DN<123>")
		)
		(pad "F4" smd circle
			(at -19.949922 -18.050002)
			(size 0.4572 0.4572)
			(layers "F.Cu" "F.Mask" "F.Paste")
			(net "GND")
		)
		(pad "F5" smd circle
			(at -18.999962 -18.050002)
			(size 0.4572 0.4572)
			(layers "F.Cu" "F.Mask" "F.Paste")
			(net "P5E_PEX0_STN7_TX_DN<125>")
		)
		(pad "F6" smd circle
			(at -18.050002 -18.050002)
			(size 0.4572 0.4572)
			(layers "F.Cu" "F.Mask" "F.Paste")
			(net "GND")
		)
		(pad "F7" smd circle
			(at -17.100042 -18.050002)
			(size 0.4572 0.4572)
			(layers "F.Cu" "F.Mask" "F.Paste")
			(net "P5E_PEX0_STN7_TX_DN<127>")
		)
		(pad "F8" smd circle
			(at -16.150082 -18.050002)
			(size 0.4572 0.4572)
			(layers "F.Cu" "F.Mask" "F.Paste")
			(net "GND")
		)
		(pad "F9" smd circle
			(at -15.200122 -18.050002)
			(size 0.4572 0.4572)
			(layers "F.Cu" "F.Mask" "F.Paste")
			(net "P5E_PEX0_STN6_TX_DN<110>")
		)
		(pad "F10" smd circle
			(at -14.249908 -18.050002)
			(size 0.4572 0.4572)
			(layers "F.Cu" "F.Mask" "F.Paste")
			(net "GND")
		)
		(pad "F11" smd circle
			(at -13.299948 -18.050002)
			(size 0.4572 0.4572)
			(layers "F.Cu" "F.Mask" "F.Paste")
			(net "P5E_PEX0_STN6_TX_DN<108>")
		)
		(pad "F12" smd circle
			(at -12.349988 -18.050002)
			(size 0.4572 0.4572)
			(layers "F.Cu" "F.Mask" "F.Paste")
			(net "GND")
		)
		(pad "F13" smd circle
			(at -11.400028 -18.050002)
			(size 0.4572 0.4572)
			(layers "F.Cu" "F.Mask" "F.Paste")
			(net "P5E_PEX0_STN6_TX_DN<106>")
		)
		(pad "F14" smd circle
			(at -10.450068 -18.050002)
			(size 0.4572 0.4572)
			(layers "F.Cu" "F.Mask" "F.Paste")
			(net "GND")
		)
		(pad "F15" smd circle
			(at -9.500108 -18.050002)
			(size 0.4572 0.4572)
			(layers "F.Cu" "F.Mask" "F.Paste")
			(net "P5E_PEX0_STN6_TX_DN<104>")
		)
		(pad "F16" smd circle
			(at -8.549894 -18.050002)
			(size 0.4572 0.4572)
			(layers "F.Cu" "F.Mask" "F.Paste")
			(net "GND")
		)
		(pad "F17" smd circle
			(at -7.599934 -18.050002)
			(size 0.4572 0.4572)
			(layers "F.Cu" "F.Mask" "F.Paste")
			(net "P5E_PEX0_STN6_TX_DN<102>")
		)
		(pad "F18" smd circle
			(at -6.649974 -18.050002)
			(size 0.4572 0.4572)
			(layers "F.Cu" "F.Mask" "F.Paste")
			(net "GND")
		)
		(pad "F19" smd circle
			(at -5.700014 -18.050002)
			(size 0.4572 0.4572)
			(layers "F.Cu" "F.Mask" "F.Paste")
			(net "P5E_PEX0_STN6_TX_DN<100>")
		)
		(pad "F20" smd circle
			(at -4.750054 -18.050002)
			(size 0.4572 0.4572)
			(layers "F.Cu" "F.Mask" "F.Paste")
			(net "GND")
		)
		(pad "F21" smd circle
			(at -3.800094 -18.050002)
			(size 0.4572 0.4572)
			(layers "F.Cu" "F.Mask" "F.Paste")
			(net "P5E_PEX0_STN6_TX_DN<98>")
		)
		(pad "F22" smd circle
			(at -2.84988 -18.050002)
			(size 0.4572 0.4572)
			(layers "F.Cu" "F.Mask" "F.Paste")
			(net "GND")
		)
		(pad "F23" smd circle
			(at -1.89992 -18.050002)
			(size 0.4572 0.4572)
			(layers "F.Cu" "F.Mask" "F.Paste")
			(net "P5E_PEX0_STN6_TX_DN<96>")
		)
		(pad "F24" smd circle
			(at -0.94996 -18.050002)
			(size 0.4572 0.4572)
			(layers "F.Cu" "F.Mask" "F.Paste")
			(net "GND")
		)
		(pad "F25" smd circle
			(at 0 -18.050002)
			(size 0.4572 0.4572)
			(layers "F.Cu" "F.Mask" "F.Paste")
			(net "P5E_PEX0_STN5_TX_DN<81>")
		)
		(pad "F26" smd circle
			(at 0.94996 -18.050002)
			(size 0.4572 0.4572)
			(layers "F.Cu" "F.Mask" "F.Paste")
			(net "GND")
		)
		(pad "F27" smd circle
			(at 1.89992 -18.050002)
			(size 0.4572 0.4572)
			(layers "F.Cu" "F.Mask" "F.Paste")
			(net "P5E_PEX0_STN5_TX_DN<83>")
		)
		(pad "F28" smd circle
			(at 2.84988 -18.050002)
			(size 0.4572 0.4572)
			(layers "F.Cu" "F.Mask" "F.Paste")
			(net "GND")
		)
		(pad "F29" smd circle
			(at 3.800094 -18.050002)
			(size 0.4572 0.4572)
			(layers "F.Cu" "F.Mask" "F.Paste")
			(net "P5E_PEX0_STN5_TX_DN<85>")
		)
		(pad "F30" smd circle
			(at 4.750054 -18.050002)
			(size 0.4572 0.4572)
			(layers "F.Cu" "F.Mask" "F.Paste")
			(net "GND")
		)
		(pad "F31" smd circle
			(at 5.700014 -18.050002)
			(size 0.4572 0.4572)
			(layers "F.Cu" "F.Mask" "F.Paste")
			(net "P5E_PEX0_STN5_TX_DN<87>")
		)
		(pad "F32" smd circle
			(at 6.649974 -18.050002)
			(size 0.4572 0.4572)
			(layers "F.Cu" "F.Mask" "F.Paste")
			(net "GND")
		)
		(pad "F33" smd circle
			(at 7.599934 -18.050002)
			(size 0.4572 0.4572)
			(layers "F.Cu" "F.Mask" "F.Paste")
			(net "P5E_PEX0_STN5_TX_DN<89>")
		)
		(pad "F34" smd circle
			(at 8.549894 -18.050002)
			(size 0.4572 0.4572)
			(layers "F.Cu" "F.Mask" "F.Paste")
			(net "GND")
		)
		(pad "F35" smd circle
			(at 9.500108 -18.050002)
			(size 0.4572 0.4572)
			(layers "F.Cu" "F.Mask" "F.Paste")
			(net "P5E_PEX0_STN5_TX_DN<91>")
		)
		(pad "F36" smd circle
			(at 10.450068 -18.050002)
			(size 0.4572 0.4572)
			(layers "F.Cu" "F.Mask" "F.Paste")
			(net "GND")
		)
		(pad "F37" smd circle
			(at 11.400028 -18.050002)
			(size 0.4572 0.4572)
			(layers "F.Cu" "F.Mask" "F.Paste")
			(net "P5E_PEX0_STN5_TX_DN<93>")
		)
		(pad "F38" smd circle
			(at 12.349988 -18.050002)
			(size 0.4572 0.4572)
			(layers "F.Cu" "F.Mask" "F.Paste")
			(net "GND")
		)
		(pad "F39" smd circle
			(at 13.299948 -18.050002)
			(size 0.4572 0.4572)
			(layers "F.Cu" "F.Mask" "F.Paste")
			(net "P5E_PEX0_STN5_TX_DN<95>")
		)
		(pad "F40" smd circle
			(at 14.249908 -18.050002)
			(size 0.4572 0.4572)
			(layers "F.Cu" "F.Mask" "F.Paste")
			(net "GND")
		)
		(pad "F41" smd circle
			(at 15.200122 -18.050002)
			(size 0.4572 0.4572)
			(layers "F.Cu" "F.Mask" "F.Paste")
			(net "P5E_PEX0_STN4_TX_DN<78>")
		)
		(pad "F42" smd circle
			(at 16.150082 -18.050002)
			(size 0.4572 0.4572)
			(layers "F.Cu" "F.Mask" "F.Paste")
			(net "GND")
		)
		(pad "F43" smd circle
			(at 17.100042 -18.050002)
			(size 0.4572 0.4572)
			(layers "F.Cu" "F.Mask" "F.Paste")
			(net "P5E_PEX0_STN4_TX_DN<76>")
		)
		(pad "F44" smd circle
			(at 18.050002 -18.050002)
			(size 0.4572 0.4572)
			(layers "F.Cu" "F.Mask" "F.Paste")
			(net "GND")
		)
		(pad "F45" smd circle
			(at 18.999962 -18.050002)
			(size 0.4572 0.4572)
			(layers "F.Cu" "F.Mask" "F.Paste")
			(net "P5E_PEX0_STN4_TX_DN<74>")
		)
		(pad "F46" smd circle
			(at 19.949922 -18.050002)
			(size 0.4572 0.4572)
			(layers "F.Cu" "F.Mask" "F.Paste")
			(net "GND")
		)
		(pad "F47" smd circle
			(at 20.899882 -18.050002)
			(size 0.4572 0.4572)
			(layers "F.Cu" "F.Mask" "F.Paste")
			(net "P5E_PEX0_STN4_TX_DN<72>")
		)
		(pad "F48" smd circle
			(at 21.850096 -18.050002)
			(size 0.4572 0.4572)
			(layers "F.Cu" "F.Mask" "F.Paste")
			(net "GND")
		)
		(pad "F49" smd circle
			(at 22.800056 -18.050002)
			(size 0.4572 0.4572)
			(layers "F.Cu" "F.Mask" "F.Paste")
			(net "GND")
		)
		(pad "G1" smd circle
			(at -22.800056 -17.100042)
			(size 0.4572 0.4572)
			(layers "F.Cu" "F.Mask" "F.Paste")
			(net "GND")
		)
		(pad "G2" smd circle
			(at -21.850096 -17.100042)
			(size 0.4572 0.4572)
			(layers "F.Cu" "F.Mask" "F.Paste")
			(net "GND")
		)
		(pad "G3" smd circle
			(at -20.899882 -17.100042)
			(size 0.4572 0.4572)
			(layers "F.Cu" "F.Mask" "F.Paste")
			(net "P5E_PEX0_STN7_TX_DP<123>")
		)
		(pad "G4" smd circle
			(at -19.949922 -17.100042)
			(size 0.4572 0.4572)
			(layers "F.Cu" "F.Mask" "F.Paste")
			(net "GND")
		)
		(pad "G5" smd circle
			(at -18.999962 -17.100042)
			(size 0.4572 0.4572)
			(layers "F.Cu" "F.Mask" "F.Paste")
			(net "P5E_PEX0_STN7_TX_DP<125>")
		)
		(pad "G6" smd circle
			(at -18.050002 -17.100042)
			(size 0.4572 0.4572)
			(layers "F.Cu" "F.Mask" "F.Paste")
			(net "GND")
		)
		(pad "G7" smd circle
			(at -17.100042 -17.100042)
			(size 0.4572 0.4572)
			(layers "F.Cu" "F.Mask" "F.Paste")
			(net "P5E_PEX0_STN7_TX_DP<127>")
		)
		(pad "G8" smd circle
			(at -16.150082 -17.100042)
			(size 0.4572 0.4572)
			(layers "F.Cu" "F.Mask" "F.Paste")
			(net "GND")
		)
		(pad "G9" smd circle
			(at -15.200122 -17.100042)
			(size 0.4572 0.4572)
			(layers "F.Cu" "F.Mask" "F.Paste")
			(net "P5E_PEX0_STN6_TX_DP<110>")
		)
		(pad "G10" smd circle
			(at -14.249908 -17.100042)
			(size 0.4572 0.4572)
			(layers "F.Cu" "F.Mask" "F.Paste")
			(net "GND")
		)
		(pad "G11" smd circle
			(at -13.299948 -17.100042)
			(size 0.4572 0.4572)
			(layers "F.Cu" "F.Mask" "F.Paste")
			(net "P5E_PEX0_STN6_TX_DP<108>")
		)
		(pad "G12" smd circle
			(at -12.349988 -17.100042)
			(size 0.4572 0.4572)
			(layers "F.Cu" "F.Mask" "F.Paste")
			(net "GND")
		)
		(pad "G13" smd circle
			(at -11.400028 -17.100042)
			(size 0.4572 0.4572)
			(layers "F.Cu" "F.Mask" "F.Paste")
			(net "P5E_PEX0_STN6_TX_DP<106>")
		)
		(pad "G14" smd circle
			(at -10.450068 -17.100042)
			(size 0.4572 0.4572)
			(layers "F.Cu" "F.Mask" "F.Paste")
			(net "GND")
		)
		(pad "G15" smd circle
			(at -9.500108 -17.100042)
			(size 0.4572 0.4572)
			(layers "F.Cu" "F.Mask" "F.Paste")
			(net "P5E_PEX0_STN6_TX_DP<104>")
		)
		(pad "G16" smd circle
			(at -8.549894 -17.100042)
			(size 0.4572 0.4572)
			(layers "F.Cu" "F.Mask" "F.Paste")
			(net "GND")
		)
		(pad "G17" smd circle
			(at -7.599934 -17.100042)
			(size 0.4572 0.4572)
			(layers "F.Cu" "F.Mask" "F.Paste")
			(net "P5E_PEX0_STN6_TX_DP<102>")
		)
		(pad "G18" smd circle
			(at -6.649974 -17.100042)
			(size 0.4572 0.4572)
			(layers "F.Cu" "F.Mask" "F.Paste")
			(net "GND")
		)
		(pad "G19" smd circle
			(at -5.700014 -17.100042)
			(size 0.4572 0.4572)
			(layers "F.Cu" "F.Mask" "F.Paste")
			(net "P5E_PEX0_STN6_TX_DP<100>")
		)
		(pad "G20" smd circle
			(at -4.750054 -17.100042)
			(size 0.4572 0.4572)
			(layers "F.Cu" "F.Mask" "F.Paste")
			(net "GND")
		)
		(pad "G21" smd circle
			(at -3.800094 -17.100042)
			(size 0.4572 0.4572)
			(layers "F.Cu" "F.Mask" "F.Paste")
			(net "P5E_PEX0_STN6_TX_DP<98>")
		)
		(pad "G22" smd circle
			(at -2.84988 -17.100042)
			(size 0.4572 0.4572)
			(layers "F.Cu" "F.Mask" "F.Paste")
			(net "GND")
		)
		(pad "G23" smd circle
			(at -1.89992 -17.100042)
			(size 0.4572 0.4572)
			(layers "F.Cu" "F.Mask" "F.Paste")
			(net "P5E_PEX0_STN6_TX_DP<96>")
		)
		(pad "G24" smd circle
			(at -0.94996 -17.100042)
			(size 0.4572 0.4572)
			(layers "F.Cu" "F.Mask" "F.Paste")
			(net "GND")
		)
		(pad "G25" smd circle
			(at 0 -17.100042)
			(size 0.4572 0.4572)
			(layers "F.Cu" "F.Mask" "F.Paste")
			(net "P5E_PEX0_STN5_TX_DP<81>")
		)
		(pad "G26" smd circle
			(at 0.94996 -17.100042)
			(size 0.4572 0.4572)
			(layers "F.Cu" "F.Mask" "F.Paste")
			(net "GND")
		)
		(pad "G27" smd circle
			(at 1.89992 -17.100042)
			(size 0.4572 0.4572)
			(layers "F.Cu" "F.Mask" "F.Paste")
			(net "P5E_PEX0_STN5_TX_DP<83>")
		)
		(pad "G28" smd circle
			(at 2.84988 -17.100042)
			(size 0.4572 0.4572)
			(layers "F.Cu" "F.Mask" "F.Paste")
			(net "GND")
		)
		(pad "G29" smd circle
			(at 3.800094 -17.100042)
			(size 0.4572 0.4572)
			(layers "F.Cu" "F.Mask" "F.Paste")
			(net "P5E_PEX0_STN5_TX_DP<85>")
		)
		(pad "G30" smd circle
			(at 4.750054 -17.100042)
			(size 0.4572 0.4572)
			(layers "F.Cu" "F.Mask" "F.Paste")
			(net "GND")
		)
		(pad "G31" smd circle
			(at 5.700014 -17.100042)
			(size 0.4572 0.4572)
			(layers "F.Cu" "F.Mask" "F.Paste")
			(net "P5E_PEX0_STN5_TX_DP<87>")
		)
		(pad "G32" smd circle
			(at 6.649974 -17.100042)
			(size 0.4572 0.4572)
			(layers "F.Cu" "F.Mask" "F.Paste")
			(net "GND")
		)
		(pad "G33" smd circle
			(at 7.599934 -17.100042)
			(size 0.4572 0.4572)
			(layers "F.Cu" "F.Mask" "F.Paste")
			(net "P5E_PEX0_STN5_TX_DP<89>")
		)
		(pad "G34" smd circle
			(at 8.549894 -17.100042)
			(size 0.4572 0.4572)
			(layers "F.Cu" "F.Mask" "F.Paste")
			(net "GND")
		)
		(pad "G35" smd circle
			(at 9.500108 -17.100042)
			(size 0.4572 0.4572)
			(layers "F.Cu" "F.Mask" "F.Paste")
			(net "P5E_PEX0_STN5_TX_DP<91>")
		)
		(pad "G36" smd circle
			(at 10.450068 -17.100042)
			(size 0.4572 0.4572)
			(layers "F.Cu" "F.Mask" "F.Paste")
			(net "GND")
		)
		(pad "G37" smd circle
			(at 11.400028 -17.100042)
			(size 0.4572 0.4572)
			(layers "F.Cu" "F.Mask" "F.Paste")
			(net "P5E_PEX0_STN5_TX_DP<93>")
		)
		(pad "G38" smd circle
			(at 12.349988 -17.100042)
			(size 0.4572 0.4572)
			(layers "F.Cu" "F.Mask" "F.Paste")
			(net "GND")
		)
		(pad "G39" smd circle
			(at 13.299948 -17.100042)
			(size 0.4572 0.4572)
			(layers "F.Cu" "F.Mask" "F.Paste")
			(net "P5E_PEX0_STN5_TX_DP<95>")
		)
		(pad "G40" smd circle
			(at 14.249908 -17.100042)
			(size 0.4572 0.4572)
			(layers "F.Cu" "F.Mask" "F.Paste")
			(net "GND")
		)
		(pad "G41" smd circle
			(at 15.200122 -17.100042)
			(size 0.4572 0.4572)
			(layers "F.Cu" "F.Mask" "F.Paste")
			(net "P5E_PEX0_STN4_TX_DP<78>")
		)
		(pad "G42" smd circle
			(at 16.150082 -17.100042)
			(size 0.4572 0.4572)
			(layers "F.Cu" "F.Mask" "F.Paste")
			(net "GND")
		)
		(pad "G43" smd circle
			(at 17.100042 -17.100042)
			(size 0.4572 0.4572)
			(layers "F.Cu" "F.Mask" "F.Paste")
			(net "P5E_PEX0_STN4_TX_DP<76>")
		)
		(pad "G44" smd circle
			(at 18.050002 -17.100042)
			(size 0.4572 0.4572)
			(layers "F.Cu" "F.Mask" "F.Paste")
			(net "GND")
		)
		(pad "G45" smd circle
			(at 18.999962 -17.100042)
			(size 0.4572 0.4572)
			(layers "F.Cu" "F.Mask" "F.Paste")
			(net "P5E_PEX0_STN4_TX_DP<74>")
		)
		(pad "G46" smd circle
			(at 19.949922 -17.100042)
			(size 0.4572 0.4572)
			(layers "F.Cu" "F.Mask" "F.Paste")
			(net "GND")
		)
		(pad "G47" smd circle
			(at 20.899882 -17.100042)
			(size 0.4572 0.4572)
			(layers "F.Cu" "F.Mask" "F.Paste")
			(net "P5E_PEX0_STN4_TX_DP<72>")
		)
		(pad "G48" smd circle
			(at 21.850096 -17.100042)
			(size 0.4572 0.4572)
			(layers "F.Cu" "F.Mask" "F.Paste")
			(net "GND")
		)
		(pad "G49" smd circle
			(at 22.800056 -17.100042)
			(size 0.4572 0.4572)
			(layers "F.Cu" "F.Mask" "F.Paste")
			(net "GND")
		)
		(pad "H1" smd circle
			(at -22.800056 -16.150082)
			(size 0.4572 0.4572)
			(layers "F.Cu" "F.Mask" "F.Paste")
			(net "P5E_PEX0_STN7_TX_DN<121>")
		)
		(pad "H2" smd circle
			(at -21.850096 -16.150082)
			(size 0.4572 0.4572)
			(layers "F.Cu" "F.Mask" "F.Paste")
			(net "P5E_PEX0_STN7_TX_DP<121>")
		)
		(pad "H3" smd circle
			(at -20.899882 -16.150082)
			(size 0.4572 0.4572)
			(layers "F.Cu" "F.Mask" "F.Paste")
			(net "GND")
		)
		(pad "H4" smd circle
			(at -19.949922 -16.150082)
			(size 0.4572 0.4572)
			(layers "F.Cu" "F.Mask" "F.Paste")
			(net "P5E_PEX0_STN7_TX_DN<124>")
		)
		(pad "H5" smd circle
			(at -18.999962 -16.150082)
			(size 0.4572 0.4572)
			(layers "F.Cu" "F.Mask" "F.Paste")
			(net "GND")
		)
	)
)
